# T6G (Grand Teton) — schematic netlist excerpt (pin names and nets, part order shuffled) for the footprints in the layout excerpt that follows; sources: Cadence DE-HDL packaged netlist, KiCad conversion of 04192023_DAF0TMB3IC0_F0TG_MB_C_brd_V02_OCP.brd

R3524  Q_RES  54.9K 1% CHIP  pkg 0402LF  page 248 : A = P3V3_AUX ; B = SMB_1_BMC_GPU_BUF_R_SDA
C55  Q_CAP_DIFFBUS  DIFF BUS_0.22UF 6.3V 20% X6S  pkg C0201  page 67 : \1\ = P5E_CPU1_P3_TX_C_DP<12> ; \2\ = P5E_CPU1_P3_TX_DP<12>
C8356  Q_CAP  1000PF 50V 5% X7R  pkg 0402  page 217 : A = PVDDIO_P1_EN_R ; B = GND

(kicad_pcb
	(version 20260206)
	(generator "pcbnew")
	(generator_version "10.0")
	(general
		(thickness 1.6)
		(legacy_teardrops no)
	)
	(paper "A4")
	(title_block
		(title "04192023_DAF0TMB3IC0_F0TG_MB_C_brd_V02_OCP.brd")
		(comment 1 "Grand Teton / footprints 1150-1152 of 8354")
	)
	(layers
		(0 "F.Cu" signal "TOP")
		(4 "In1.Cu" signal "GND")
		(6 "In2.Cu" signal "IN1")
		(8 "In3.Cu" signal "GND1")
		(10 "In4.Cu" signal "IN2")
		(12 "In5.Cu" signal "GND2")
		(14 "In6.Cu" signal "IN3")
		(16 "In7.Cu" signal "GND3")
		(18 "In8.Cu" signal "VCC")
		(20 "In9.Cu" signal "VCC1")
		(22 "In10.Cu" signal "GND4")
		(24 "In11.Cu" signal "IN4")
		(26 "In12.Cu" signal "GND5")
		(28 "In13.Cu" signal "IN5")
		(30 "In14.Cu" signal "GND6")
		(32 "In15.Cu" signal "IN6")
		(34 "In16.Cu" signal "GND7")
		(2 "B.Cu" signal "BOTTOM")
		(9 "F.Adhes" user "F.Adhesive")
		(11 "B.Adhes" user "B.Adhesive")
		(13 "F.Paste" user "Package Geometry/Pastemask Top")
		(15 "B.Paste" user "Package Geometry/Pastemask Bottom")
		(5 "F.SilkS" user "Ref Des/Silkscreen Top")
		(7 "B.SilkS" user "Ref Des/Silkscreen Bottom")
		(1 "F.Mask" user "Board Geometry/Soldermask Top")
		(3 "B.Mask" user "Board Geometry/Soldermask Bottom")
		(17 "Dwgs.User" user "User.Drawings")
		(19 "Cmts.User" user "User.Comments")
		(21 "Eco1.User" user "User.Eco1")
		(23 "Eco2.User" user "User.Eco2")
		(25 "Edge.Cuts" user "Board Geometry/Outline")
		(27 "Margin" user)
		(31 "F.CrtYd" user "Package Geometry/Place Bound Top")
		(29 "B.CrtYd" user "Package Geometry/Place Bound Bottom")
		(35 "F.Fab" user "Ref Des/Assembly Top")
		(33 "B.Fab" user "Ref Des/Assembly Bottom")
	)
	(footprint ""
		(layer "F.Cu")
		(at 35.132772 -433.112164 180)
		(property "Reference" "R3524"
			(at 0 0 180)
			(layer "F.SilkS")
			(hide yes)
			(effects
				(font
					(size 1.27 1.27)
				)
			)
		)
		(property "Value" ""
			(at 0 0 180)
			(layer "F.Fab")
			(effects
				(font
					(size 1.27 1.27)
				)
			)
		)
		(duplicate_pad_numbers_are_jumpers no)
		(fp_line
			(start 0.7874 0.4064)
			(end -0.7874 0.4064)
			(stroke
				(width 0.1524)
				(type default)
			)
			(layer "F.SilkS")
		)
		(fp_line
			(start 0.7874 -0.4064)
			(end 0.7874 0.4064)
			(stroke
				(width 0.1524)
				(type default)
			)
			(layer "F.SilkS")
		)
		(fp_line
			(start -0.7874 0.4064)
			(end -0.7874 -0.4064)
			(stroke
				(width 0.1524)
				(type default)
			)
			(layer "F.SilkS")
		)
		(fp_line
			(start -0.7874 -0.4064)
			(end 0.7874 -0.4064)
			(stroke
				(width 0.1524)
				(type default)
			)
			(layer "F.SilkS")
		)
		(fp_line
			(start 0.67945 0.3048)
			(end 0.120396 0.3048)
			(stroke
				(width 0.1)
				(type default)
			)
			(layer "F.Fab")
		)
		(fp_line
			(start 0.67945 -0.3048)
			(end 0.67945 0.3048)
			(stroke
				(width 0.1)
				(type default)
			)
			(layer "F.Fab")
		)
		(fp_line
			(start 0.12065 -0.2794)
			(end 0.12065 -0.3048)
			(stroke
				(width 0.1)
				(type default)
			)
			(layer "F.Fab")
		)
		(fp_line
			(start 0.12065 -0.3048)
			(end 0.67945 -0.3048)
			(stroke
				(width 0.1)
				(type default)
			)
			(layer "F.Fab")
		)
		(fp_line
			(start 0.120396 0.3048)
			(end 0.120396 0.2794)
			(stroke
				(width 0.1)
				(type default)
			)
			(layer "F.Fab")
		)
		(fp_line
			(start 0.120396 0.2794)
			(end -0.12065 0.2794)
			(stroke
				(width 0.1)
				(type default)
			)
			(layer "F.Fab")
		)
		(fp_line
			(start -0.12065 0.3048)
			(end -0.67945 0.3048)
			(stroke
				(width 0.1)
				(type default)
			)
			(layer "F.Fab")
		)
		(fp_line
			(start -0.12065 0.2794)
			(end -0.12065 0.3048)
			(stroke
				(width 0.1)
				(type default)
			)
			(layer "F.Fab")
		)
		(fp_line
			(start -0.12065 -0.2794)
			(end 0.12065 -0.2794)
			(stroke
				(width 0.1)
				(type default)
			)
			(layer "F.Fab")
		)
		(fp_line
			(start -0.12065 -0.305054)
			(end -0.12065 -0.2794)
			(stroke
				(width 0.1)
				(type default)
			)
			(layer "F.Fab")
		)
		(fp_line
			(start -0.67945 0.3048)
			(end -0.67945 -0.305054)
			(stroke
				(width 0.1)
				(type default)
			)
			(layer "F.Fab")
		)
		(fp_line
			(start -0.67945 -0.305054)
			(end -0.12065 -0.305054)
			(stroke
				(width 0.1)
				(type default)
			)
			(layer "F.Fab")
		)
		(pad "1" smd circle
			(at -0.40005 0 180)
			(size 0 0)
			(layers "F.Cu" "F.Mask" "F.Paste")
			(net "P3V3_AUX")
		)
		(pad "2" smd circle
			(at 0.40005 0 180)
			(size 0 0)
			(layers "F.Cu" "F.Mask" "F.Paste")
			(net "SMB_1_BMC_GPU_BUF_R_SDA")
		)
	)
	(footprint ""
		(layer "F.Cu")
		(at 19.400012 -358.30637 -90)
		(property "Reference" "C8356"
			(at 0 0 270)
			(layer "F.SilkS")
			(hide yes)
			(effects
				(font
					(size 1.27 1.27)
				)
			)
		)
		(property "Value" ""
			(at 0 0 270)
			(layer "F.Fab")
			(effects
				(font
					(size 1.27 1.27)
				)
			)
		)
		(duplicate_pad_numbers_are_jumpers no)
		(fp_line
			(start -0.7874 0.4064)
			(end -0.7874 -0.4064)
			(stroke
				(width 0.1524)
				(type default)
			)
			(layer "F.SilkS")
		)
		(fp_line
			(start 0.7874 0.4064)
			(end -0.7874 0.4064)
			(stroke
				(width 0.1524)
				(type default)
			)
			(layer "F.SilkS")
		)
		(fp_line
			(start -0.7874 -0.4064)
			(end 0.7874 -0.4064)
			(stroke
				(width 0.1524)
				(type default)
			)
			(layer "F.SilkS")
		)
		(fp_line
			(start 0.7874 -0.4064)
			(end 0.7874 0.4064)
			(stroke
				(width 0.1524)
				(type default)
			)
			(layer "F.SilkS")
		)
		(fp_line
			(start -0.67945 0.3048)
			(end -0.67945 -0.305054)
			(stroke
				(width 0.1)
				(type default)
			)
			(layer "F.Fab")
		)
		(fp_line
			(start -0.12065 0.3048)
			(end -0.67945 0.3048)
			(stroke
				(width 0.1)
				(type default)
			)
			(layer "F.Fab")
		)
		(fp_line
			(start 0.120396 0.3048)
			(end 0.120396 0.2794)
			(stroke
				(width 0.1)
				(type default)
			)
			(layer "F.Fab")
		)
		(fp_line
			(start 0.67945 0.3048)
			(end 0.120396 0.3048)
			(stroke
				(width 0.1)
				(type default)
			)
			(layer "F.Fab")
		)
		(fp_line
			(start -0.12065 0.2794)
			(end -0.12065 0.3048)
			(stroke
				(width 0.1)
				(type default)
			)
			(layer "F.Fab")
		)
		(fp_line
			(start 0.120396 0.2794)
			(end -0.12065 0.2794)
			(stroke
				(width 0.1)
				(type default)
			)
			(layer "F.Fab")
		)
		(fp_line
			(start -0.12065 -0.2794)
			(end 0.12065 -0.2794)
			(stroke
				(width 0.1)
				(type default)
			)
			(layer "F.Fab")
		)
		(fp_line
			(start 0.12065 -0.2794)
			(end 0.12065 -0.3048)
			(stroke
				(width 0.1)
				(type default)
			)
			(layer "F.Fab")
		)
		(fp_line
			(start 0.12065 -0.3048)
			(end 0.67945 -0.3048)
			(stroke
				(width 0.1)
				(type default)
			)
			(layer "F.Fab")
		)
		(fp_line
			(start 0.67945 -0.3048)
			(end 0.67945 0.3048)
			(stroke
				(width 0.1)
				(type default)
			)
			(layer "F.Fab")
		)
		(fp_line
			(start -0.67945 -0.305054)
			(end -0.12065 -0.305054)
			(stroke
				(width 0.1)
				(type default)
			)
			(layer "F.Fab")
		)
		(fp_line
			(start -0.12065 -0.305054)
			(end -0.12065 -0.2794)
			(stroke
				(width 0.1)
				(type default)
			)
			(layer "F.Fab")
		)
		(pad "1" smd circle
			(at -0.40005 0 270)
			(size 0 0)
			(layers "F.Cu" "F.Mask" "F.Paste")
			(net "PVDDIO_P1_EN_R")
		)
		(pad "2" smd circle
			(at 0.40005 0 270)
			(size 0 0)
			(layers "F.Cu" "F.Mask" "F.Paste")
			(net "GND")
		)
	)
	(footprint ""
		(layer "F.Cu")
		(at 132.213096 -370.57203 -90)
		(property "Reference" "C55"
			(at 0 0 270)
			(layer "F.SilkS")
			(hide yes)
			(effects
				(font
					(size 1.27 1.27)
				)
			)
		)
		(property "Value" ""
			(at 0 0 270)
			(layer "F.Fab")
			(effects
				(font
					(size 1.27 1.27)
				)
			)
		)
		(duplicate_pad_numbers_are_jumpers no)
		(fp_line
			(start -0.299974 0.150114)
			(end -0.299974 -0.150114)
			(stroke
				(width 0.1)
				(type default)
			)
			(layer "F.Fab")
		)
		(fp_line
			(start 0.299974 0.150114)
			(end -0.299974 0.150114)
			(stroke
				(width 0.1)
				(type default)
			)
			(layer "F.Fab")
		)
		(fp_line
			(start -0.299974 -0.150114)
			(end 0.299974 -0.150114)
			(stroke
				(width 0.1)
				(type default)
			)
			(layer "F.Fab")
		)
		(fp_line
			(start 0.299974 -0.150114)
			(end 0.299974 0.150114)
			(stroke
				(width 0.1)
				(type default)
			)
			(layer "F.Fab")
		)
		(pad "1" smd rect
			(at -0.2667 0 270)
			(size 0.3048 0.381)
			(layers "F.Cu" "F.Mask" "F.Paste")
			(net "P5E_CPU1_P3_TX_C_DP<12>")
		)
		(pad "2" smd rect
			(at 0.2667 0 270)
			(size 0.3048 0.381)
			(layers "F.Cu" "F.Mask" "F.Paste")
			(net "P5E_CPU1_P3_TX_DP<12>")
		)
	)
)
